(kicad_pcb
	(version 20260206)
	(generator "pcbnew")
	(generator_version "10.0")
	(general
		(thickness 1.6)
		(legacy_teardrops no)
	)
	(paper "A4")
	(title_block
		(title "03242023_DA0F0TMBIJ0_F0T_Motherboard_J_brd_V01_OCP.brd")
		(comment 1 "Grand Teton / footprints 497-500 of 6105")
	)
	(layers
		(0 "F.Cu" signal "TOP")
		(4 "In1.Cu" signal "GND")
		(6 "In2.Cu" signal "IN1")
		(8 "In3.Cu" signal "GND1")
		(10 "In4.Cu" signal "IN2")
		(12 "In5.Cu" signal "GND2")
		(14 "In6.Cu" signal "IN3")
		(16 "In7.Cu" signal "GND3")
		(18 "In8.Cu" signal "VCC")
		(20 "In9.Cu" signal "VCC1")
		(22 "In10.Cu" signal "GND4")
		(24 "In11.Cu" signal "IN4")
		(26 "In12.Cu" signal "GND5")
		(28 "In13.Cu" signal "IN5")
		(30 "In14.Cu" signal "GND6")
		(32 "In15.Cu" signal "IN6")
		(34 "In16.Cu" signal "GND7")
		(2 "B.Cu" signal "BOTTOM")
		(9 "F.Adhes" user "F.Adhesive")
		(11 "B.Adhes" user "B.Adhesive")
		(13 "F.Paste" user "Package Geometry/Pastemask Top")
		(15 "B.Paste" user "Package Geometry/Pastemask Bottom")
		(5 "F.SilkS" user "Ref Des/Silkscreen Top")
		(7 "B.SilkS" user "Ref Des/Silkscreen Bottom")
		(1 "F.Mask" user "Board Geometry/Soldermask Top")
		(3 "B.Mask" user "Board Geometry/Soldermask Bottom")
		(17 "Dwgs.User" user "User.Drawings")
		(19 "Cmts.User" user "User.Comments")
		(21 "Eco1.User" user "User.Eco1")
		(23 "Eco2.User" user "User.Eco2")
		(25 "Edge.Cuts" user "Board Geometry/Outline")
		(27 "Margin" user)
		(31 "F.CrtYd" user "Package Geometry/Place Bound Top")
		(29 "B.CrtYd" user "Package Geometry/Place Bound Bottom")
		(35 "F.Fab" user "Ref Des/Assembly Top")
		(33 "B.Fab" user "Ref Des/Assembly Bottom")
	)
	(footprint ""
		(layer "F.Cu")
		(at 164.14115 -432.865276 -90)
		(property "Reference" "R2667"
			(at 0 0 270)
			(layer "F.SilkS")
			(hide yes)
			(effects
				(font
					(size 1.27 1.27)
				)
			)
		)
		(property "Value" ""
			(at 0 0 270)
			(layer "F.Fab")
			(effects
				(font
					(size 1.27 1.27)
				)
			)
		)
		(duplicate_pad_numbers_are_jumpers no)
		(fp_line
			(start -0.7874 0.4064)
			(end -0.7874 -0.4064)
			(stroke
				(width 0.1524)
				(type default)
			)
			(layer "F.SilkS")
		)
		(fp_line
			(start 0.7874 0.4064)
			(end -0.7874 0.4064)
			(stroke
				(width 0.1524)
				(type default)
			)
			(layer "F.SilkS")
		)
		(fp_line
			(start -0.7874 -0.4064)
			(end 0.7874 -0.4064)
			(stroke
				(width 0.1524)
				(type default)
			)
			(layer "F.SilkS")
		)
		(fp_line
			(start 0.7874 -0.4064)
			(end 0.7874 0.4064)
			(stroke
				(width 0.1524)
				(type default)
			)
			(layer "F.SilkS")
		)
		(fp_line
			(start -0.67945 0.3048)
			(end -0.67945 -0.305054)
			(stroke
				(width 0.1)
				(type default)
			)
			(layer "F.Fab")
		)
		(fp_line
			(start -0.12065 0.3048)
			(end -0.67945 0.3048)
			(stroke
				(width 0.1)
				(type default)
			)
			(layer "F.Fab")
		)
		(fp_line
			(start 0.120396 0.3048)
			(end 0.120396 0.2794)
			(stroke
				(width 0.1)
				(type default)
			)
			(layer "F.Fab")
		)
		(fp_line
			(start 0.67945 0.3048)
			(end 0.120396 0.3048)
			(stroke
				(width 0.1)
				(type default)
			)
			(layer "F.Fab")
		)
		(fp_line
			(start -0.12065 0.2794)
			(end -0.12065 0.3048)
			(stroke
				(width 0.1)
				(type default)
			)
			(layer "F.Fab")
		)
		(fp_line
			(start 0.120396 0.2794)
			(end -0.12065 0.2794)
			(stroke
				(width 0.1)
				(type default)
			)
			(layer "F.Fab")
		)
		(fp_line
			(start -0.12065 -0.2794)
			(end 0.12065 -0.2794)
			(stroke
				(width 0.1)
				(type default)
			)
			(layer "F.Fab")
		)
		(fp_line
			(start 0.12065 -0.2794)
			(end 0.12065 -0.3048)
			(stroke
				(width 0.1)
				(type default)
			)
			(layer "F.Fab")
		)
		(fp_line
			(start 0.12065 -0.3048)
			(end 0.67945 -0.3048)
			(stroke
				(width 0.1)
				(type default)
			)
			(layer "F.Fab")
		)
		(fp_line
			(start 0.67945 -0.3048)
			(end 0.67945 0.3048)
			(stroke
				(width 0.1)
				(type default)
			)
			(layer "F.Fab")
		)
		(fp_line
			(start -0.67945 -0.305054)
			(end -0.12065 -0.305054)
			(stroke
				(width 0.1)
				(type default)
			)
			(layer "F.Fab")
		)
		(fp_line
			(start -0.12065 -0.305054)
			(end -0.12065 -0.2794)
			(stroke
				(width 0.1)
				(type default)
			)
			(layer "F.Fab")
		)
		(pad "1" smd circle
			(at -0.40005 0 270)
			(size 0 0)
			(layers "F.Cu" "F.Mask" "F.Paste")
			(net "P3V3_AUX")
		)
		(pad "2" smd circle
			(at 0.40005 0 270)
			(size 0 0)
			(layers "F.Cu" "F.Mask" "F.Paste")
			(net "SMB_BMC_SWB_BUF_R_SCL")
		)
	)
	(footprint ""
		(layer "F.Cu")
		(at 105.132886 -324.445376)
		(property "Reference" "PL30"
			(at -12.69492 7.099554 90)
			(unlocked yes)
			(layer "F.SilkS")
			(effects
				(font
					(size 0.7874 0.5842)
					(thickness 0.1524)
				)
				(justify left)
			)
		)
		(property "Value" ""
			(at 0 0 0)
			(layer "F.Fab")
			(effects
				(font
					(size 1.27 1.27)
				)
			)
		)
		(duplicate_pad_numbers_are_jumpers no)
		(fp_line
			(start -3.750056 -5.500116)
			(end -2.393442 -5.500116)
			(stroke
				(width 0.1524)
				(type default)
			)
			(layer "F.SilkS")
		)
		(fp_line
			(start -3.750056 5.500116)
			(end -3.750056 -5.500116)
			(stroke
				(width 0.1524)
				(type default)
			)
			(layer "F.SilkS")
		)
		(fp_line
			(start -2.393442 5.500116)
			(end -3.750056 5.500116)
			(stroke
				(width 0.1524)
				(type default)
			)
			(layer "F.SilkS")
		)
		(fp_line
			(start 2.393442 5.500116)
			(end 3.750056 5.500116)
			(stroke
				(width 0.1524)
				(type default)
			)
			(layer "F.SilkS")
		)
		(fp_line
			(start 3.750056 -5.500116)
			(end 2.393442 -5.500116)
			(stroke
				(width 0.1524)
				(type default)
			)
			(layer "F.SilkS")
		)
		(fp_line
			(start 3.750056 5.500116)
			(end 3.750056 -5.500116)
			(stroke
				(width 0.1524)
				(type default)
			)
			(layer "F.SilkS")
		)
		(fp_poly
			(pts
				(xy -3.418586 -6.86943) (xy -3.05943 -5.791708) (xy -4.136898 -6.150864)
			)
			(stroke
				(width 0)
				(type default)
			)
			(fill yes)
			(layer "F.SilkS")
		)
		(fp_line
			(start -3.750056 -5.500116)
			(end -3.750056 5.500116)
			(stroke
				(width 0.1)
				(type default)
			)
			(layer "F.Fab")
		)
		(fp_line
			(start -3.750056 5.500116)
			(end 3.750056 5.500116)
			(stroke
				(width 0.1)
				(type default)
			)
			(layer "F.Fab")
		)
		(fp_line
			(start 3.750056 -5.500116)
			(end -3.750056 -5.500116)
			(stroke
				(width 0.1)
				(type default)
			)
			(layer "F.Fab")
		)
		(fp_line
			(start 3.750056 5.500116)
			(end 3.750056 -5.500116)
			(stroke
				(width 0.1)
				(type default)
			)
			(layer "F.Fab")
		)
		(fp_poly
			(pts
				(xy -4.9276 -4.757928) (xy -4.9276 -3.741928) (xy -3.9116 -4.249928)
			)
			(stroke
				(width 0)
				(type default)
			)
			(fill yes)
			(layer "F.Fab")
		)
		(pad "1" smd rect
			(at 0 -4.249928 270)
			(size 2.413 4.5212)
			(layers "F.Cu" "F.Mask" "F.Paste")
			(net "SW_PVCCIN_CPU1_SW2")
		)
		(pad "2" smd rect
			(at 0 -1.175004 270)
			(size 1.3716 4.5212)
			(layers "F.Cu" "F.Mask" "F.Paste")
			(net "IND_P1_CPL2")
		)
		(pad "3" smd rect
			(at 0 1.175004 270)
			(size 1.3716 4.5212)
			(layers "F.Cu" "F.Mask" "F.Paste")
			(net "IND_P1_CPL1")
		)
		(pad "4" smd rect
			(at 0 4.249928 270)
			(size 2.413 4.5212)
			(layers "F.Cu" "F.Mask" "F.Paste")
			(net "PVCCIN_CPU1")
		)
	)
	(footprint ""
		(layer "F.Cu")
		(at 349.014034 -68.21678)
		(property "Reference" "C147"
			(at 0 0 0)
			(layer "F.SilkS")
			(hide yes)
			(effects
				(font
					(size 1.27 1.27)
				)
			)
		)
		(property "Value" ""
			(at 0 0 0)
			(layer "F.Fab")
			(effects
				(font
					(size 1.27 1.27)
				)
			)
		)
		(duplicate_pad_numbers_are_jumpers no)
		(fp_line
			(start -0.299974 -0.150114)
			(end 0.299974 -0.150114)
			(stroke
				(width 0.1)
				(type default)
			)
			(layer "F.Fab")
		)
		(fp_line
			(start -0.299974 0.150114)
			(end -0.299974 -0.150114)
			(stroke
				(width 0.1)
				(type default)
			)
			(layer "F.Fab")
		)
		(fp_line
			(start 0.299974 -0.150114)
			(end 0.299974 0.150114)
			(stroke
				(width 0.1)
				(type default)
			)
			(layer "F.Fab")
		)
		(fp_line
			(start 0.299974 0.150114)
			(end -0.299974 0.150114)
			(stroke
				(width 0.1)
				(type default)
			)
			(layer "F.Fab")
		)
		(pad "1" smd rect
			(at -0.2667 0)
			(size 0.3048 0.381)
			(layers "F.Cu" "F.Mask" "F.Paste")
			(net "DMI_CPU0_PCH_TX_C_DN<3>")
		)
		(pad "2" smd rect
			(at 0.2667 0)
			(size 0.3048 0.381)
			(layers "F.Cu" "F.Mask" "F.Paste")
			(net "DMI_CPU0_PCH_TX_DN<3>")
		)
	)
	(footprint ""
		(layer "F.Cu")
		(at 299.02023 -48.304196 180)
		(property "Reference" "R2973"
			(at 0 0 180)
			(layer "F.SilkS")
			(hide yes)
			(effects
				(font
					(size 1.27 1.27)
				)
			)
		)
		(property "Value" ""
			(at 0 0 180)
			(layer "F.Fab")
			(effects
				(font
					(size 1.27 1.27)
				)
			)
		)
		(duplicate_pad_numbers_are_jumpers no)
		(fp_line
			(start 0.7874 0.4064)
			(end -0.7874 0.4064)
			(stroke
				(width 0.1524)
				(type default)
			)
			(layer "F.SilkS")
		)
		(fp_line
			(start 0.7874 -0.4064)
			(end 0.7874 0.4064)
			(stroke
				(width 0.1524)
				(type default)
			)
			(layer "F.SilkS")
		)
		(fp_line
			(start -0.7874 0.4064)
			(end -0.7874 -0.4064)
			(stroke
				(width 0.1524)
				(type default)
			)
			(layer "F.SilkS")
		)
		(fp_line
			(start -0.7874 -0.4064)
			(end 0.7874 -0.4064)
			(stroke
				(width 0.1524)
				(type default)
			)
			(layer "F.SilkS")
		)
		(fp_line
			(start 0.67945 0.3048)
			(end 0.120396 0.3048)
			(stroke
				(width 0.1)
				(type default)
			)
			(layer "F.Fab")
		)
		(fp_line
			(start 0.67945 -0.3048)
			(end 0.67945 0.3048)
			(stroke
				(width 0.1)
				(type default)
			)
			(layer "F.Fab")
		)
		(fp_line
			(start 0.12065 -0.2794)
			(end 0.12065 -0.3048)
			(stroke
				(width 0.1)
				(type default)
			)
			(layer "F.Fab")
		)
		(fp_line
			(start 0.12065 -0.3048)
			(end 0.67945 -0.3048)
			(stroke
				(width 0.1)
				(type default)
			)
			(layer "F.Fab")
		)
		(fp_line
			(start 0.120396 0.3048)
			(end 0.120396 0.2794)
			(stroke
				(width 0.1)
				(type default)
			)
			(layer "F.Fab")
		)
		(fp_line
			(start 0.120396 0.2794)
			(end -0.12065 0.2794)
			(stroke
				(width 0.1)
				(type default)
			)
			(layer "F.Fab")
		)
		(fp_line
			(start -0.12065 0.3048)
			(end -0.67945 0.3048)
			(stroke
				(width 0.1)
				(type default)
			)
			(layer "F.Fab")
		)
		(fp_line
			(start -0.12065 0.2794)
			(end -0.12065 0.3048)
			(stroke
				(width 0.1)
				(type default)
			)
			(layer "F.Fab")
		)
		(fp_line
			(start -0.12065 -0.2794)
			(end 0.12065 -0.2794)
			(stroke
				(width 0.1)
				(type default)
			)
			(layer "F.Fab")
		)
		(fp_line
			(start -0.12065 -0.305054)
			(end -0.12065 -0.2794)
			(stroke
				(width 0.1)
				(type default)
			)
			(layer "F.Fab")
		)
		(fp_line
			(start -0.67945 0.3048)
			(end -0.67945 -0.305054)
			(stroke
				(width 0.1)
				(type default)
			)
			(layer "F.Fab")
		)
		(fp_line
			(start -0.67945 -0.305054)
			(end -0.12065 -0.305054)
			(stroke
				(width 0.1)
				(type default)
			)
			(layer "F.Fab")
		)
		(pad "1" smd circle
			(at -0.40005 0 180)
			(size 0 0)
			(layers "F.Cu" "F.Mask" "F.Paste")
			(net "FAB_REV_ID2")
		)
		(pad "2" smd circle
			(at 0.40005 0 180)
			(size 0 0)
			(layers "F.Cu" "F.Mask" "F.Paste")
			(net "GND")
		)
	)
)
